# S9S_MB_2U (Grand Teton) — schematic netlist excerpt (pin names and nets, part order shuffled) for the footprints in the layout excerpt that follows; sources: Cadence DE-HDL packaged netlist, KiCad conversion of 03242023_DA0F0TMBIJ0_F0T_Motherboard_J_brd_V01_OCP.brd

D45  SCHOTTKY_12  B0530WS7F IC  pkg SOD323XB  page 115 : A = PWRGD_FAIL_CPU0_GH_R1 ; C = P3V3_AUX
R2511  Q_RES  1K 1% EMPTY  pkg 0402LF  page 184 : A = FM_M2_E1S_E6_PEDET ; B = GND

(kicad_pcb
	(version 20260206)
	(generator "pcbnew")
	(generator_version "10.0")
	(general
		(thickness 1.6)
		(legacy_teardrops no)
	)
	(paper "A4")
	(title_block
		(title "03242023_DA0F0TMBIJ0_F0T_Motherboard_J_brd_V01_OCP.brd")
		(comment 1 "Grand Teton / footprints 5083-5084 of 6105")
	)
	(layers
		(0 "F.Cu" signal "TOP")
		(4 "In1.Cu" signal "GND")
		(6 "In2.Cu" signal "IN1")
		(8 "In3.Cu" signal "GND1")
		(10 "In4.Cu" signal "IN2")
		(12 "In5.Cu" signal "GND2")
		(14 "In6.Cu" signal "IN3")
		(16 "In7.Cu" signal "GND3")
		(18 "In8.Cu" signal "VCC")
		(20 "In9.Cu" signal "VCC1")
		(22 "In10.Cu" signal "GND4")
		(24 "In11.Cu" signal "IN4")
		(26 "In12.Cu" signal "GND5")
		(28 "In13.Cu" signal "IN5")
		(30 "In14.Cu" signal "GND6")
		(32 "In15.Cu" signal "IN6")
		(34 "In16.Cu" signal "GND7")
		(2 "B.Cu" signal "BOTTOM")
		(9 "F.Adhes" user "F.Adhesive")
		(11 "B.Adhes" user "B.Adhesive")
		(13 "F.Paste" user "Package Geometry/Pastemask Top")
		(15 "B.Paste" user "Package Geometry/Pastemask Bottom")
		(5 "F.SilkS" user "Ref Des/Silkscreen Top")
		(7 "B.SilkS" user "Ref Des/Silkscreen Bottom")
		(1 "F.Mask" user "Board Geometry/Soldermask Top")
		(3 "B.Mask" user "Board Geometry/Soldermask Bottom")
		(17 "Dwgs.User" user "User.Drawings")
		(19 "Cmts.User" user "User.Comments")
		(21 "Eco1.User" user "User.Eco1")
		(23 "Eco2.User" user "User.Eco2")
		(25 "Edge.Cuts" user "Board Geometry/Outline")
		(27 "Margin" user)
		(31 "F.CrtYd" user "Package Geometry/Place Bound Top")
		(29 "B.CrtYd" user "Package Geometry/Place Bound Bottom")
		(35 "F.Fab" user "Ref Des/Assembly Top")
		(33 "B.Fab" user "Ref Des/Assembly Bottom")
	)
	(footprint ""
		(layer "B.Cu")
		(at 459.574646 -315.26099 -90)
		(property "Reference" "D45"
			(at 3.189732 1.218946 0)
			(unlocked yes)
			(layer "B.SilkS")
			(effects
				(font
					(size 0.7874 0.5842)
					(thickness 0.1524)
				)
				(justify left mirror)
			)
		)
		(property "Value" ""
			(at 0 0 90)
			(layer "B.Fab")
			(effects
				(font
					(size 1.27 1.27)
				)
				(justify mirror)
			)
		)
		(duplicate_pad_numbers_are_jumpers no)
		(fp_line
			(start -2.050796 0.700024)
			(end 2.050796 0.700024)
			(stroke
				(width 0.1524)
				(type default)
			)
			(layer "B.SilkS")
		)
		(fp_line
			(start 2.050796 0.700024)
			(end 2.050796 -0.700024)
			(stroke
				(width 0.1524)
				(type default)
			)
			(layer "B.SilkS")
		)
		(fp_line
			(start -2.343404 0.6985)
			(end -2.216404 0.6985)
			(stroke
				(width 0.1524)
				(type default)
			)
			(layer "B.SilkS")
		)
		(fp_line
			(start -2.229104 0.6985)
			(end -2.051304 0.6985)
			(stroke
				(width 0.1524)
				(type default)
			)
			(layer "B.SilkS")
		)
		(fp_line
			(start -2.051304 0.6985)
			(end -2.051304 0.635)
			(stroke
				(width 0.1524)
				(type default)
			)
			(layer "B.SilkS")
		)
		(fp_line
			(start -2.152904 0.635)
			(end -2.152904 -0.6985)
			(stroke
				(width 0.1524)
				(type default)
			)
			(layer "B.SilkS")
		)
		(fp_line
			(start -2.051304 0.635)
			(end -2.152904 0.635)
			(stroke
				(width 0.1524)
				(type default)
			)
			(layer "B.SilkS")
		)
		(fp_line
			(start 0.30607 0.500126)
			(end -0.193802 0)
			(stroke
				(width 0.1524)
				(type default)
			)
			(layer "B.SilkS")
		)
		(fp_line
			(start -0.193802 0)
			(end 0.30607 -0.500126)
			(stroke
				(width 0.1524)
				(type default)
			)
			(layer "B.SilkS")
		)
		(fp_line
			(start -0.293878 -0.500126)
			(end -0.293878 0.500126)
			(stroke
				(width 0.1524)
				(type default)
			)
			(layer "B.SilkS")
		)
		(fp_line
			(start 0.30607 -0.500126)
			(end 0.30607 0.500126)
			(stroke
				(width 0.1524)
				(type default)
			)
			(layer "B.SilkS")
		)
		(fp_line
			(start -2.064004 -0.6731)
			(end -2.064004 -0.6985)
			(stroke
				(width 0.1524)
				(type default)
			)
			(layer "B.SilkS")
		)
		(fp_line
			(start -2.343404 -0.6985)
			(end -2.343404 0.6985)
			(stroke
				(width 0.1524)
				(type default)
			)
			(layer "B.SilkS")
		)
		(fp_line
			(start -2.229104 -0.6985)
			(end -2.229104 0.6985)
			(stroke
				(width 0.1524)
				(type default)
			)
			(layer "B.SilkS")
		)
		(fp_line
			(start -2.152904 -0.6985)
			(end -2.343404 -0.6985)
			(stroke
				(width 0.1524)
				(type default)
			)
			(layer "B.SilkS")
		)
		(fp_line
			(start -2.064004 -0.6985)
			(end -2.229104 -0.6985)
			(stroke
				(width 0.1524)
				(type default)
			)
			(layer "B.SilkS")
		)
		(fp_line
			(start -2.050796 -0.700024)
			(end -2.050796 0.700024)
			(stroke
				(width 0.1524)
				(type default)
			)
			(layer "B.SilkS")
		)
		(fp_line
			(start 2.050796 -0.700024)
			(end -2.050796 -0.700024)
			(stroke
				(width 0.1524)
				(type default)
			)
			(layer "B.SilkS")
		)
		(fp_line
			(start -0.899922 0.700024)
			(end 0.899922 0.700024)
			(stroke
				(width 0.1)
				(type default)
			)
			(layer "B.Fab")
		)
		(fp_line
			(start 0.899922 0.700024)
			(end 0.899922 -0.700024)
			(stroke
				(width 0.1)
				(type default)
			)
			(layer "B.Fab")
		)
		(fp_line
			(start -0.899922 -0.700024)
			(end -0.899922 0.700024)
			(stroke
				(width 0.1)
				(type default)
			)
			(layer "B.Fab")
		)
		(fp_line
			(start 0.899922 -0.700024)
			(end -0.899922 -0.700024)
			(stroke
				(width 0.1)
				(type default)
			)
			(layer "B.Fab")
		)
		(fp_text user "+"
			(at 3.123946 0.762 180)
			(unlocked yes)
			(layer "B.SilkS")
			(effects
				(font
					(size 1.905 1.4224)
					(thickness 0.1524)
				)
				(justify left mirror)
			)
		)
		(fp_text user "-"
			(at -2.003298 -3.303524 90)
			(unlocked yes)
			(layer "B.SilkS")
			(effects
				(font
					(size 1.905 1.4224)
					(thickness 0.1524)
				)
				(justify left mirror)
			)
		)
		(fp_text user "+"
			(at 3.123946 0.762 180)
			(unlocked yes)
			(layer "B.Fab")
			(effects
				(font
					(size 1.905 1.4224)
					(thickness 0.1524)
				)
				(justify left mirror)
			)
		)
		(fp_text user "-"
			(at -3.880104 0.23495 90)
			(unlocked yes)
			(layer "B.Fab")
			(effects
				(font
					(size 1.905 1.4224)
					(thickness 0.1524)
				)
				(justify left mirror)
			)
		)
		(pad "1" smd rect
			(at 1.199896 0 180)
			(size 0.6604 1.3716)
			(layers "B.Cu" "B.Mask" "B.Paste")
			(net "PWRGD_FAIL_CPU0_GH_R1")
		)
		(pad "2" smd rect
			(at -1.199896 0)
			(size 0.6604 1.3716)
			(layers "B.Cu" "B.Mask" "B.Paste")
			(net "P3V3_AUX")
		)
	)
	(footprint ""
		(layer "B.Cu")
		(at 372.41988 -36.921948 180)
		(property "Reference" "R2511"
			(at 0 0 0)
			(layer "B.SilkS")
			(hide yes)
			(effects
				(font
					(size 1.27 1.27)
				)
				(justify mirror)
			)
		)
		(property "Value" ""
			(at 0 0 0)
			(layer "B.Fab")
			(effects
				(font
					(size 1.27 1.27)
				)
				(justify mirror)
			)
		)
		(duplicate_pad_numbers_are_jumpers no)
		(fp_line
			(start 0.7874 0.4064)
			(end 0.7874 -0.4064)
			(stroke
				(width 0.1524)
				(type default)
			)
			(layer "B.SilkS")
		)
		(fp_line
			(start 0.7874 -0.4064)
			(end -0.7874 -0.4064)
			(stroke
				(width 0.1524)
				(type default)
			)
			(layer "B.SilkS")
		)
		(fp_line
			(start -0.7874 0.4064)
			(end 0.7874 0.4064)
			(stroke
				(width 0.1524)
				(type default)
			)
			(layer "B.SilkS")
		)
		(fp_line
			(start -0.7874 -0.4064)
			(end -0.7874 0.4064)
			(stroke
				(width 0.1524)
				(type default)
			)
			(layer "B.SilkS")
		)
		(fp_line
			(start 0.67945 0.3048)
			(end 0.67945 -0.305054)
			(stroke
				(width 0.1)
				(type default)
			)
			(layer "B.Fab")
		)
		(fp_line
			(start 0.67945 -0.305054)
			(end 0.12065 -0.305054)
			(stroke
				(width 0.1)
				(type default)
			)
			(layer "B.Fab")
		)
		(fp_line
			(start 0.12065 0.3048)
			(end 0.67945 0.3048)
			(stroke
				(width 0.1)
				(type default)
			)
			(layer "B.Fab")
		)
		(fp_line
			(start 0.12065 0.2794)
			(end 0.12065 0.3048)
			(stroke
				(width 0.1)
				(type default)
			)
			(layer "B.Fab")
		)
		(fp_line
			(start 0.12065 -0.2794)
			(end -0.12065 -0.2794)
			(stroke
				(width 0.1)
				(type default)
			)
			(layer "B.Fab")
		)
		(fp_line
			(start 0.12065 -0.305054)
			(end 0.12065 -0.2794)
			(stroke
				(width 0.1)
				(type default)
			)
			(layer "B.Fab")
		)
		(fp_line
			(start -0.120396 0.3048)
			(end -0.120396 0.2794)
			(stroke
				(width 0.1)
				(type default)
			)
			(layer "B.Fab")
		)
		(fp_line
			(start -0.120396 0.2794)
			(end 0.12065 0.2794)
			(stroke
				(width 0.1)
				(type default)
			)
			(layer "B.Fab")
		)
		(fp_line
			(start -0.12065 -0.2794)
			(end -0.12065 -0.3048)
			(stroke
				(width 0.1)
				(type default)
			)
			(layer "B.Fab")
		)
		(fp_line
			(start -0.12065 -0.3048)
			(end -0.67945 -0.3048)
			(stroke
				(width 0.1)
				(type default)
			)
			(layer "B.Fab")
		)
		(fp_line
			(start -0.67945 0.3048)
			(end -0.120396 0.3048)
			(stroke
				(width 0.1)
				(type default)
			)
			(layer "B.Fab")
		)
		(fp_line
			(start -0.67945 -0.3048)
			(end -0.67945 0.3048)
			(stroke
				(width 0.1)
				(type default)
			)
			(layer "B.Fab")
		)
		(pad "1" smd circle
			(at 0.40005 0)
			(size 0 0)
			(layers "B.Cu" "B.Mask" "B.Paste")
			(net "FM_M2_E1S_E6_PEDET")
		)
		(pad "2" smd circle
			(at -0.40005 0)
			(size 0 0)
			(layers "B.Cu" "B.Mask" "B.Paste")
			(net "GND")
		)
	)
)
